# T6G (Grand Teton) — schematic netlist excerpt (pin names and nets, part order shuffled) for the footprints in the layout excerpt that follows; sources: Cadence DE-HDL packaged netlist, KiCad conversion of 04192023_DAF0TMB3IC0_F0TG_MB_C_brd_V02_OCP.brd

R720  Q_RES  4.7K 5% EMPTY  pkg 0201LF  page 320 : A = P1V8_CPU1_RT_1D ; B = TEST1_RT_CPU1_P0
R25  Q_RES  10K 1% CHIP  pkg 0402LF  page 83 : A = FM_I3C_CPU1_MUX1_OE_N ; B = GND
PR2514  Q_RES  10 1% CHIP  pkg 0402LF  page 266 : A = P12V_HSC_ADC_P ; B = P12V_HSC_SENSE1_P

(kicad_pcb
	(version 20260206)
	(generator "pcbnew")
	(generator_version "10.0")
	(general
		(thickness 1.6)
		(legacy_teardrops no)
	)
	(paper "A4")
	(title_block
		(title "04192023_DAF0TMB3IC0_F0TG_MB_C_brd_V02_OCP.brd")
		(comment 1 "Grand Teton / footprints 6399-6401 of 8354")
	)
	(layers
		(0 "F.Cu" signal "TOP")
		(4 "In1.Cu" signal "GND")
		(6 "In2.Cu" signal "IN1")
		(8 "In3.Cu" signal "GND1")
		(10 "In4.Cu" signal "IN2")
		(12 "In5.Cu" signal "GND2")
		(14 "In6.Cu" signal "IN3")
		(16 "In7.Cu" signal "GND3")
		(18 "In8.Cu" signal "VCC")
		(20 "In9.Cu" signal "VCC1")
		(22 "In10.Cu" signal "GND4")
		(24 "In11.Cu" signal "IN4")
		(26 "In12.Cu" signal "GND5")
		(28 "In13.Cu" signal "IN5")
		(30 "In14.Cu" signal "GND6")
		(32 "In15.Cu" signal "IN6")
		(34 "In16.Cu" signal "GND7")
		(2 "B.Cu" signal "BOTTOM")
		(9 "F.Adhes" user "F.Adhesive")
		(11 "B.Adhes" user "B.Adhesive")
		(13 "F.Paste" user "Package Geometry/Pastemask Top")
		(15 "B.Paste" user "Package Geometry/Pastemask Bottom")
		(5 "F.SilkS" user "Ref Des/Silkscreen Top")
		(7 "B.SilkS" user "Ref Des/Silkscreen Bottom")
		(1 "F.Mask" user "Board Geometry/Soldermask Top")
		(3 "B.Mask" user "Board Geometry/Soldermask Bottom")
		(17 "Dwgs.User" user "User.Drawings")
		(19 "Cmts.User" user "User.Comments")
		(21 "Eco1.User" user "User.Eco1")
		(23 "Eco2.User" user "User.Eco2")
		(25 "Edge.Cuts" user "Board Geometry/Outline")
		(27 "Margin" user)
		(31 "F.CrtYd" user "Package Geometry/Place Bound Top")
		(29 "B.CrtYd" user "Package Geometry/Place Bound Bottom")
		(35 "F.Fab" user "Ref Des/Assembly Top")
		(33 "B.Fab" user "Ref Des/Assembly Bottom")
	)
	(footprint ""
		(layer "B.Cu")
		(at 208.461356 -387.676136)
		(property "Reference" "PR2514"
			(at 0 0 0)
			(layer "B.SilkS")
			(hide yes)
			(effects
				(font
					(size 1.27 1.27)
				)
				(justify mirror)
			)
		)
		(property "Value" ""
			(at 0 0 0)
			(layer "B.Fab")
			(effects
				(font
					(size 1.27 1.27)
				)
				(justify mirror)
			)
		)
		(duplicate_pad_numbers_are_jumpers no)
		(fp_line
			(start -0.7874 -0.4064)
			(end -0.7874 0.4064)
			(stroke
				(width 0.1524)
				(type default)
			)
			(layer "B.SilkS")
		)
		(fp_line
			(start -0.7874 0.4064)
			(end 0.7874 0.4064)
			(stroke
				(width 0.1524)
				(type default)
			)
			(layer "B.SilkS")
		)
		(fp_line
			(start 0.7874 -0.4064)
			(end -0.7874 -0.4064)
			(stroke
				(width 0.1524)
				(type default)
			)
			(layer "B.SilkS")
		)
		(fp_line
			(start 0.7874 0.4064)
			(end 0.7874 -0.4064)
			(stroke
				(width 0.1524)
				(type default)
			)
			(layer "B.SilkS")
		)
		(fp_line
			(start -0.67945 -0.3048)
			(end -0.67945 0.3048)
			(stroke
				(width 0.1)
				(type default)
			)
			(layer "B.Fab")
		)
		(fp_line
			(start -0.67945 0.3048)
			(end -0.120396 0.3048)
			(stroke
				(width 0.1)
				(type default)
			)
			(layer "B.Fab")
		)
		(fp_line
			(start -0.12065 -0.3048)
			(end -0.67945 -0.3048)
			(stroke
				(width 0.1)
				(type default)
			)
			(layer "B.Fab")
		)
		(fp_line
			(start -0.12065 -0.2794)
			(end -0.12065 -0.3048)
			(stroke
				(width 0.1)
				(type default)
			)
			(layer "B.Fab")
		)
		(fp_line
			(start -0.120396 0.2794)
			(end 0.12065 0.2794)
			(stroke
				(width 0.1)
				(type default)
			)
			(layer "B.Fab")
		)
		(fp_line
			(start -0.120396 0.3048)
			(end -0.120396 0.2794)
			(stroke
				(width 0.1)
				(type default)
			)
			(layer "B.Fab")
		)
		(fp_line
			(start 0.12065 -0.305054)
			(end 0.12065 -0.2794)
			(stroke
				(width 0.1)
				(type default)
			)
			(layer "B.Fab")
		)
		(fp_line
			(start 0.12065 -0.2794)
			(end -0.12065 -0.2794)
			(stroke
				(width 0.1)
				(type default)
			)
			(layer "B.Fab")
		)
		(fp_line
			(start 0.12065 0.2794)
			(end 0.12065 0.3048)
			(stroke
				(width 0.1)
				(type default)
			)
			(layer "B.Fab")
		)
		(fp_line
			(start 0.12065 0.3048)
			(end 0.67945 0.3048)
			(stroke
				(width 0.1)
				(type default)
			)
			(layer "B.Fab")
		)
		(fp_line
			(start 0.67945 -0.305054)
			(end 0.12065 -0.305054)
			(stroke
				(width 0.1)
				(type default)
			)
			(layer "B.Fab")
		)
		(fp_line
			(start 0.67945 0.3048)
			(end 0.67945 -0.305054)
			(stroke
				(width 0.1)
				(type default)
			)
			(layer "B.Fab")
		)
		(pad "1" smd circle
			(at 0.40005 0 180)
			(size 0 0)
			(layers "B.Cu" "B.Mask" "B.Paste")
			(net "P12V_HSC_ADC_P")
		)
		(pad "2" smd circle
			(at -0.40005 0 180)
			(size 0 0)
			(layers "B.Cu" "B.Mask" "B.Paste")
			(net "P12V_HSC_SENSE1_P")
		)
	)
	(footprint ""
		(layer "B.Cu")
		(at 164.266626 -109.076998 90)
		(property "Reference" "R25"
			(at 0 0 90)
			(layer "B.SilkS")
			(hide yes)
			(effects
				(font
					(size 1.27 1.27)
				)
				(justify mirror)
			)
		)
		(property "Value" ""
			(at 0 0 90)
			(layer "B.Fab")
			(effects
				(font
					(size 1.27 1.27)
				)
				(justify mirror)
			)
		)
		(duplicate_pad_numbers_are_jumpers no)
		(fp_line
			(start 0.7874 -0.4064)
			(end -0.7874 -0.4064)
			(stroke
				(width 0.1524)
				(type default)
			)
			(layer "B.SilkS")
		)
		(fp_line
			(start -0.7874 -0.4064)
			(end -0.7874 0.4064)
			(stroke
				(width 0.1524)
				(type default)
			)
			(layer "B.SilkS")
		)
		(fp_line
			(start 0.7874 0.4064)
			(end 0.7874 -0.4064)
			(stroke
				(width 0.1524)
				(type default)
			)
			(layer "B.SilkS")
		)
		(fp_line
			(start -0.7874 0.4064)
			(end 0.7874 0.4064)
			(stroke
				(width 0.1524)
				(type default)
			)
			(layer "B.SilkS")
		)
		(fp_line
			(start 0.67945 -0.305054)
			(end 0.12065 -0.305054)
			(stroke
				(width 0.1)
				(type default)
			)
			(layer "B.Fab")
		)
		(fp_line
			(start 0.12065 -0.305054)
			(end 0.12065 -0.2794)
			(stroke
				(width 0.1)
				(type default)
			)
			(layer "B.Fab")
		)
		(fp_line
			(start -0.12065 -0.3048)
			(end -0.67945 -0.3048)
			(stroke
				(width 0.1)
				(type default)
			)
			(layer "B.Fab")
		)
		(fp_line
			(start -0.67945 -0.3048)
			(end -0.67945 0.3048)
			(stroke
				(width 0.1)
				(type default)
			)
			(layer "B.Fab")
		)
		(fp_line
			(start 0.12065 -0.2794)
			(end -0.12065 -0.2794)
			(stroke
				(width 0.1)
				(type default)
			)
			(layer "B.Fab")
		)
		(fp_line
			(start -0.12065 -0.2794)
			(end -0.12065 -0.3048)
			(stroke
				(width 0.1)
				(type default)
			)
			(layer "B.Fab")
		)
		(fp_line
			(start 0.12065 0.2794)
			(end 0.12065 0.3048)
			(stroke
				(width 0.1)
				(type default)
			)
			(layer "B.Fab")
		)
		(fp_line
			(start -0.120396 0.2794)
			(end 0.12065 0.2794)
			(stroke
				(width 0.1)
				(type default)
			)
			(layer "B.Fab")
		)
		(fp_line
			(start 0.67945 0.3048)
			(end 0.67945 -0.305054)
			(stroke
				(width 0.1)
				(type default)
			)
			(layer "B.Fab")
		)
		(fp_line
			(start 0.12065 0.3048)
			(end 0.67945 0.3048)
			(stroke
				(width 0.1)
				(type default)
			)
			(layer "B.Fab")
		)
		(fp_line
			(start -0.120396 0.3048)
			(end -0.120396 0.2794)
			(stroke
				(width 0.1)
				(type default)
			)
			(layer "B.Fab")
		)
		(fp_line
			(start -0.67945 0.3048)
			(end -0.120396 0.3048)
			(stroke
				(width 0.1)
				(type default)
			)
			(layer "B.Fab")
		)
		(pad "1" smd circle
			(at 0.40005 0 270)
			(size 0 0)
			(layers "B.Cu" "B.Mask" "B.Paste")
			(net "FM_I3C_CPU1_MUX1_OE_N")
		)
		(pad "2" smd circle
			(at -0.40005 0 270)
			(size 0 0)
			(layers "B.Cu" "B.Mask" "B.Paste")
			(net "GND")
		)
	)
	(footprint ""
		(layer "B.Cu")
		(at 43.265852 -385.09956 180)
		(property "Reference" "R720"
			(at 0 0 0)
			(layer "B.SilkS")
			(hide yes)
			(effects
				(font
					(size 1.27 1.27)
				)
				(justify mirror)
			)
		)
		(property "Value" ""
			(at 0 0 0)
			(layer "B.Fab")
			(effects
				(font
					(size 1.27 1.27)
				)
				(justify mirror)
			)
		)
		(duplicate_pad_numbers_are_jumpers no)
		(fp_line
			(start 0.32512 0.175006)
			(end 0.32512 -0.175006)
			(stroke
				(width 0.1)
				(type default)
			)
			(layer "B.Fab")
		)
		(fp_line
			(start 0.32512 -0.175006)
			(end -0.32512 -0.175006)
			(stroke
				(width 0.1)
				(type default)
			)
			(layer "B.Fab")
		)
		(fp_line
			(start -0.32512 0.175006)
			(end 0.32512 0.175006)
			(stroke
				(width 0.1)
				(type default)
			)
			(layer "B.Fab")
		)
		(fp_line
			(start -0.32512 -0.175006)
			(end -0.32512 0.175006)
			(stroke
				(width 0.1)
				(type default)
			)
			(layer "B.Fab")
		)
		(pad "1" smd rect
			(at 0.2667 0)
			(size 0.3048 0.381)
			(layers "B.Cu" "B.Mask" "B.Paste")
			(net "P1V8_CPU1_RT_1D")
		)
		(pad "2" smd rect
			(at -0.2667 0 180)
			(size 0.3048 0.381)
			(layers "B.Cu" "B.Mask" "B.Paste")
			(net "TEST1_RT_CPU1_P0")
		)
	)
)
